(kicad_pcb
	(version 20241229)
	(generator "pcbnew")
	(generator_version "9.0")
	(general
		(thickness 1.6)
		(legacy_teardrops no)
	)
	(paper "A4")
	(title_block
		(title "OCuLink to PCIe adapter")
		(date "2025-06-18")
		(rev "1.0.0")
		(company "Antmicro Ltd")
		(comment 1 "www.antmicro.com")
		(comment 9 "footprints 119-123 of 159")
	)
	(layers
		(0 "F.Cu" signal)
		(4 "In1.Cu" signal)
		(6 "In2.Cu" signal)
		(2 "B.Cu" signal)
		(9 "F.Adhes" user "F.Adhesive")
		(11 "B.Adhes" user "B.Adhesive")
		(13 "F.Paste" user)
		(15 "B.Paste" user)
		(5 "F.SilkS" user "F.Silkscreen")
		(7 "B.SilkS" user "B.Silkscreen")
		(1 "F.Mask" user)
		(3 "B.Mask" user)
		(17 "Dwgs.User" user "User.Drawings")
		(19 "Cmts.User" user "User.Comments")
		(21 "Eco1.User" user "User.Eco1")
		(23 "Eco2.User" user "User.Eco2")
		(25 "Edge.Cuts" user)
		(27 "Margin" user)
		(31 "F.CrtYd" user "F.Courtyard")
		(29 "B.CrtYd" user "B.Courtyard")
		(35 "F.Fab" user)
		(33 "B.Fab" user)
	)
	(footprint "antmicro-footprints:R_0402_1005Metric"
		(layer "F.Cu")
		(at 120.5 132.8 180)
		(descr "Resistor SMD 0402")
		(tags "resistor SMD 0402")
		(property "Reference" "R5"
			(at 3.3 0.4 180)
			(layer "F.SilkS")
			(effects
				(font
					(size 0.7 0.7)
					(thickness 0.15)
				)
				(justify left top)
			)
		)
		(property "Value" "R_68k_0402"
			(at -1.011843 1.772046 0)
			(layer "F.Fab")
			(effects
				(font
					(size 0.7 0.7)
					(thickness 0.15)
				)
				(justify right top)
			)
		)
		(property "Datasheet" "https://www.bourns.com/docs/product-datasheets/cr.pdf"
			(at 0 0 0)
			(layer "F.Fab")
			(hide yes)
			(effects
				(font
					(size 1.27 1.27)
					(thickness 0.15)
				)
			)
		)
		(property "Description" "SMD Chip Resistor"
			(at 0 0 0)
			(layer "F.Fab")
			(hide yes)
			(effects
				(font
					(size 1.27 1.27)
					(thickness 0.15)
				)
			)
		)
		(property "MPN" "CR0402-FX-6802GLF"
			(at 0 0 180)
			(unlocked yes)
			(layer "F.Fab")
			(hide yes)
			(effects
				(font
					(size 1 1)
					(thickness 0.15)
				)
			)
		)
		(property "Manufacturer" "Bourns"
			(at 0 0 180)
			(unlocked yes)
			(layer "F.Fab")
			(hide yes)
			(effects
				(font
					(size 1 1)
					(thickness 0.15)
				)
			)
		)
		(property "License" "Apache-2.0"
			(at 0 0 180)
			(unlocked yes)
			(layer "F.Fab")
			(hide yes)
			(effects
				(font
					(size 1 1)
					(thickness 0.15)
				)
			)
		)
		(property "Author" "Antmicro"
			(at 0 0 180)
			(unlocked yes)
			(layer "F.Fab")
			(hide yes)
			(effects
				(font
					(size 1 1)
					(thickness 0.15)
				)
			)
		)
		(property "Val" "68k"
			(at 0 0 180)
			(unlocked yes)
			(layer "F.Fab")
			(hide yes)
			(effects
				(font
					(size 1 1)
					(thickness 0.15)
				)
			)
		)
		(property "Tolerance" "1%"
			(at 0 0 180)
			(unlocked yes)
			(layer "F.Fab")
			(hide yes)
			(effects
				(font
					(size 1 1)
					(thickness 0.15)
				)
			)
		)
		(sheetname "/Power/")
		(sheetfile "power.kicad_sch")
		(attr smd exclude_from_bom dnp)
		(fp_rect
			(start -0.925 -0.47)
			(end 0.925 0.47)
			(stroke
				(width 0.05)
				(type default)
			)
			(fill no)
			(layer "F.CrtYd")
		)
		(fp_rect
			(start -0.5 -0.25)
			(end 0.5 0.25)
			(stroke
				(width 0.15)
				(type solid)
			)
			(fill no)
			(layer "F.Fab")
		)
		(fp_text user "License: Apache-2.0"
			(at -0.949999 5.169 0)
			(layer "F.Fab")
			(effects
				(font
					(size 0.7 0.7)
					(thickness 0.15)
				)
				(justify right top)
			)
		)
		(fp_text user "Author: Antmicro"
			(at -0.95 4.169 0)
			(layer "F.Fab")
			(effects
				(font
					(size 0.7 0.7)
					(thickness 0.15)
				)
				(justify right top)
			)
		)
		(fp_text user "${REFERENCE}"
			(at 0 0 0)
			(layer "F.Fab")
			(effects
				(font
					(size 0.7 0.7)
					(thickness 0.15)
				)
				(justify right top)
			)
		)
		(pad "1" smd roundrect
			(at -0.48 0 180)
			(size 0.59 0.64)
			(layers "F.Cu" "F.Mask" "F.Paste")
			(roundrect_rratio 0.25)
			(net 107 "/Power/3V3_MODE")
			(pintype "passive")
		)
		(pad "2" smd roundrect
			(at 0.48 0 180)
			(size 0.59 0.64)
			(layers "F.Cu" "F.Mask" "F.Paste")
			(roundrect_rratio 0.25)
			(net 88 "/Power/3V3_VCC")
			(pintype "passive")
		)
	)
	(footprint "antmicro-footprints:C_0402_1005Metric"
		(layer "F.Cu")
		(at 154.9 47.62 90)
		(descr "Capacitor SMD 0402")
		(tags "capacitor SMD 0402")
		(property "Reference" "C38"
			(at 1.02 1.699999 90)
			(layer "F.SilkS")
			(effects
				(font
					(size 0.7 0.7)
					(thickness 0.15)
				)
				(justify right top)
			)
		)
		(property "Value" "C_1u_25V_0402"
			(at -1.022927 2.155213 90)
			(layer "F.Fab")
			(effects
				(font
					(size 0.7 0.7)
					(thickness 0.15)
				)
				(justify left bottom)
			)
		)
		(property "Datasheet" "https://www.murata.com/products/productdetail?partno=GRM155R61E105KE11%23"
			(at 0 0 90)
			(layer "F.Fab")
			(hide yes)
			(effects
				(font
					(size 1.27 1.27)
					(thickness 0.15)
				)
			)
		)
		(property "Description" "SMD Multilayer Ceramic Capacitor, 1 µF, 25 V, 0402 [1005 Metric], ± 10%, X5R, GRM Series"
			(at 0 0 90)
			(layer "F.Fab")
			(hide yes)
			(effects
				(font
					(size 1.27 1.27)
					(thickness 0.15)
				)
			)
		)
		(property "MPN" "GRM155R61E105KE11J"
			(at 0 0 90)
			(unlocked yes)
			(layer "F.Fab")
			(hide yes)
			(effects
				(font
					(size 1 1)
					(thickness 0.15)
				)
			)
		)
		(property "Manufacturer" "Murata"
			(at 0 0 90)
			(unlocked yes)
			(layer "F.Fab")
			(hide yes)
			(effects
				(font
					(size 1 1)
					(thickness 0.15)
				)
			)
		)
		(property "License" "Apache-2.0"
			(at 0 0 90)
			(unlocked yes)
			(layer "F.Fab")
			(hide yes)
			(effects
				(font
					(size 1 1)
					(thickness 0.15)
				)
			)
		)
		(property "Author" "Antmicro"
			(at 0 0 90)
			(unlocked yes)
			(layer "F.Fab")
			(hide yes)
			(effects
				(font
					(size 1 1)
					(thickness 0.15)
				)
			)
		)
		(property "Val" "1u"
			(at 0 0 90)
			(unlocked yes)
			(layer "F.Fab")
			(hide yes)
			(effects
				(font
					(size 1 1)
					(thickness 0.15)
				)
			)
		)
		(property "Voltage" "25V"
			(at 0 0 90)
			(unlocked yes)
			(layer "F.Fab")
			(hide yes)
			(effects
				(font
					(size 1 1)
					(thickness 0.15)
				)
			)
		)
		(property "Dielectric" "X5R"
			(at 0 0 90)
			(unlocked yes)
			(layer "F.Fab")
			(hide yes)
			(effects
				(font
					(size 1 1)
					(thickness 0.15)
				)
			)
		)
		(sheetname "/USB-PD/")
		(sheetfile "usb-pd.kicad_sch")
		(attr smd dnp)
		(fp_rect
			(start -0.925 -0.47)
			(end 0.925 0.47)
			(stroke
				(width 0.05)
				(type default)
			)
			(fill no)
			(layer "F.CrtYd")
		)
		(fp_line
			(start 0.504 -0.25)
			(end 0.504 0.248)
			(stroke
				(width 0.15)
				(type solid)
			)
			(layer "F.Fab")
		)
		(fp_line
			(start -0.494 -0.25)
			(end 0.504 -0.25)
			(stroke
				(width 0.15)
				(type solid)
			)
			(layer "F.Fab")
		)
		(fp_line
			(start 0.504 0.248)
			(end -0.494 0.248)
			(stroke
				(width 0.15)
				(type solid)
			)
			(layer "F.Fab")
		)
		(fp_line
			(start -0.494 0.248)
			(end -0.494 -0.25)
			(stroke
				(width 0.15)
				(type solid)
			)
			(layer "F.Fab")
		)
		(fp_text user "License: Apache-2.0"
			(at -0.939 5.799 90)
			(layer "F.Fab")
			(effects
				(font
					(size 0.7 0.7)
					(thickness 0.15)
				)
				(justify left bottom)
			)
		)
		(fp_text user "${REFERENCE}"
			(at 0 0 270)
			(layer "F.Fab")
			(effects
				(font
					(size 0.7 0.7)
					(thickness 0.15)
				)
				(justify right top)
			)
		)
		(fp_text user "Author: Antmicro"
			(at -0.939 3.399 90)
			(layer "F.Fab")
			(effects
				(font
					(size 0.7 0.7)
					(thickness 0.15)
				)
				(justify left bottom)
			)
		)
		(pad "1" smd roundrect
			(at -0.48 0 90)
			(size 0.59 0.64)
			(layers "F.Cu" "F.Mask" "F.Paste")
			(roundrect_rratio 0.25)
			(net 84 "Net-(Q6-G)")
			(pintype "passive")
		)
		(pad "2" smd roundrect
			(at 0.48 0 90)
			(size 0.59 0.64)
			(layers "F.Cu" "F.Mask" "F.Paste")
			(roundrect_rratio 0.25)
			(net 115 "/USB-PD/VCC")
			(pintype "passive")
		)
	)
	(footprint "antmicro-footprints:C_Pol_Vishay-T59-EE"
		(layer "F.Cu")
		(at 127.9 110 180)
		(property "Reference" "C29"
			(at -4.9 -0.2 180)
			(layer "F.SilkS")
			(effects
				(font
					(size 0.7 0.7)
					(thickness 0.15)
				)
				(justify left bottom)
			)
		)
		(property "Value" "C_Pol_150u_30V_Vishay-T59-EE"
			(at -5.08 5.08 180)
			(unlocked yes)
			(layer "F.Fab")
			(effects
				(font
					(size 0.7 0.7)
					(thickness 0.15)
				)
				(justify left bottom)
			)
		)
		(property "Datasheet" "https://www.vishay.com/docs/40191/t59.pdf"
			(at 0 0 0)
			(layer "F.Fab")
			(hide yes)
			(effects
				(font
					(size 1.27 1.27)
					(thickness 0.15)
				)
			)
		)
		(property "Description" "Tantalum Capacitors - Polymer 150uF 30volts 20% 75mohms maxESR"
			(at 0 0 0)
			(layer "F.Fab")
			(hide yes)
			(effects
				(font
					(size 1.27 1.27)
					(thickness 0.15)
				)
			)
		)
		(property "MPN" "T59EE157M030C0075"
			(at 0 0 180)
			(unlocked yes)
			(layer "F.Fab")
			(hide yes)
			(effects
				(font
					(size 1 1)
					(thickness 0.15)
				)
			)
		)
		(property "Manufacturer" "Vishay"
			(at 0 0 180)
			(unlocked yes)
			(layer "F.Fab")
			(hide yes)
			(effects
				(font
					(size 1 1)
					(thickness 0.15)
				)
			)
		)
		(property "Voltage" "30V"
			(at 0 0 180)
			(unlocked yes)
			(layer "F.Fab")
			(hide yes)
			(effects
				(font
					(size 1 1)
					(thickness 0.15)
				)
			)
		)
		(property "Val" "150u"
			(at 0 0 180)
			(unlocked yes)
			(layer "F.Fab")
			(hide yes)
			(effects
				(font
					(size 1 1)
					(thickness 0.15)
				)
			)
		)
		(property "Author" "Antmicro"
			(at 0 0 180)
			(unlocked yes)
			(layer "F.Fab")
			(hide yes)
			(effects
				(font
					(size 1 1)
					(thickness 0.15)
				)
			)
		)
		(property "License" "Apache-2.0"
			(at 0 0 180)
			(unlocked yes)
			(layer "F.Fab")
			(hide yes)
			(effects
				(font
					(size 1 1)
					(thickness 0.15)
				)
			)
		)
		(property "Dielectric" "template_dielectric"
			(at 0 0 180)
			(unlocked yes)
			(layer "F.Fab")
			(hide yes)
			(effects
				(font
					(size 1 1)
					(thickness 0.15)
				)
			)
		)
		(sheetname "/Power/")
		(sheetfile "power.kicad_sch")
		(attr smd)
		(fp_line
			(start -2 2.25)
			(end 2 2.25)
			(stroke
				(width 0.15)
				(type solid)
			)
			(layer "F.SilkS")
		)
		(fp_line
			(start -2 -2.25)
			(end 2 -2.25)
			(stroke
				(width 0.15)
				(type solid)
			)
			(layer "F.SilkS")
		)
		(fp_line
			(start -3.5 -2.8)
			(end -3.5 -3.2)
			(stroke
				(width 0.15)
				(type solid)
			)
			(layer "F.SilkS")
		)
		(fp_line
			(start -3.7 -3)
			(end -3.3 -3)
			(stroke
				(width 0.15)
				(type solid)
			)
			(layer "F.SilkS")
		)
		(fp_rect
			(start -4.9 -2.9)
			(end 4.9 2.9)
			(stroke
				(width 0.05)
				(type solid)
			)
			(fill no)
			(layer "F.CrtYd")
		)
		(fp_rect
			(start -3.75 -2.25)
			(end 3.75 2.25)
			(stroke
				(width 0.15)
				(type solid)
			)
			(fill no)
			(layer "F.Fab")
		)
		(fp_text user "Author: Antmicro"
			(at -5.079999 7.08 0)
			(layer "F.Fab")
			(effects
				(font
					(size 0.7 0.7)
					(thickness 0.15)
				)
				(justify right top)
			)
		)
		(fp_text user "License: Apache-2.0"
			(at -5.08 9.48 0)
			(layer "F.Fab")
			(effects
				(font
					(size 0.7 0.7)
					(thickness 0.15)
				)
				(justify right top)
			)
		)
		(fp_text user "${REFERENCE}"
			(at 0 -0.175 180)
			(layer "F.Fab")
			(effects
				(font
					(size 0.7 0.7)
					(thickness 0.15)
				)
				(justify left bottom)
			)
		)
		(pad "1" smd trapezoid
			(at -3.4 0 180)
			(size 2.5 5.3)
			(layers "F.Cu" "F.Mask" "F.Paste")
			(net 87 "+12V")
			(pintype "passive")
		)
		(pad "2" smd trapezoid
			(at 3.4 0 180)
			(size 2.5 5.3)
			(layers "F.Cu" "F.Mask" "F.Paste")
			(net 66 "GND")
			(pintype "passive")
		)
	)
	(footprint "antmicro-footprints:C_0402_1005Metric"
		(layer "F.Cu")
		(at 142.502 87.95 180)
		(descr "Capacitor SMD 0402")
		(tags "capacitor SMD 0402")
		(property "Reference" "C27"
			(at 0.902 0.35 180)
			(layer "F.SilkS")
			(effects
				(font
					(size 0.7 0.7)
					(thickness 0.15)
				)
				(justify right top)
			)
		)
		(property "Value" "C_100n_0402"
			(at -1.022927 2.155213 0)
			(layer "F.Fab")
			(effects
				(font
					(size 0.7 0.7)
					(thickness 0.15)
				)
				(justify right top)
			)
		)
		(property "Datasheet" "https://www.murata.com/products/productdetail?partno=GRM155R61H104KE14%23"
			(at 0 0 0)
			(layer "F.Fab")
			(hide yes)
			(effects
				(font
					(size 1.27 1.27)
					(thickness 0.15)
				)
			)
		)
		(property "Description" "SMD Multilayer Ceramic Capacitor, 0.1 µF, 50 V, 0402 [1005 Metric], ± 10%, X5R, GRM Series"
			(at 0 0 0)
			(layer "F.Fab")
			(hide yes)
			(effects
				(font
					(size 1.27 1.27)
					(thickness 0.15)
				)
			)
		)
		(property "MPN" "GRM155R61H104KE14D"
			(at 0 0 180)
			(unlocked yes)
			(layer "F.Fab")
			(hide yes)
			(effects
				(font
					(size 1 1)
					(thickness 0.15)
				)
			)
		)
		(property "Val" "100n"
			(at 0 0 180)
			(unlocked yes)
			(layer "F.Fab")
			(hide yes)
			(effects
				(font
					(size 1 1)
					(thickness 0.15)
				)
			)
		)
		(property "Voltage" "50V"
			(at 0 0 180)
			(unlocked yes)
			(layer "F.Fab")
			(hide yes)
			(effects
				(font
					(size 1 1)
					(thickness 0.15)
				)
			)
		)
		(property "Dielectric" "X5R"
			(at 0 0 180)
			(unlocked yes)
			(layer "F.Fab")
			(hide yes)
			(effects
				(font
					(size 1 1)
					(thickness 0.15)
				)
			)
		)
		(property "Manufacturer" "Murata"
			(at 0 0 180)
			(unlocked yes)
			(layer "F.Fab")
			(hide yes)
			(effects
				(font
					(size 1 1)
					(thickness 0.15)
				)
			)
		)
		(property "License" "Apache-2.0"
			(at 0 0 180)
			(unlocked yes)
			(layer "F.Fab")
			(hide yes)
			(effects
				(font
					(size 1 1)
					(thickness 0.15)
				)
			)
		)
		(property "Author" "Antmicro"
			(at 0 0 180)
			(unlocked yes)
			(layer "F.Fab")
			(hide yes)
			(effects
				(font
					(size 1 1)
					(thickness 0.15)
				)
			)
		)
		(sheetname "/USB-PD/")
		(sheetfile "usb-pd.kicad_sch")
		(attr smd)
		(fp_rect
			(start -0.925 -0.47)
			(end 0.925 0.47)
			(stroke
				(width 0.05)
				(type default)
			)
			(fill no)
			(layer "F.CrtYd")
		)
		(fp_line
			(start 0.504 0.248)
			(end -0.494 0.248)
			(stroke
				(width 0.15)
				(type solid)
			)
			(layer "F.Fab")
		)
		(fp_line
			(start 0.504 -0.25)
			(end 0.504 0.248)
			(stroke
				(width 0.15)
				(type solid)
			)
			(layer "F.Fab")
		)
		(fp_line
			(start -0.494 0.248)
			(end -0.494 -0.25)
			(stroke
				(width 0.15)
				(type solid)
			)
			(layer "F.Fab")
		)
		(fp_line
			(start -0.494 -0.25)
			(end 0.504 -0.25)
			(stroke
				(width 0.15)
				(type solid)
			)
			(layer "F.Fab")
		)
		(fp_text user "License: Apache-2.0"
			(at -0.939 5.799 0)
			(layer "F.Fab")
			(effects
				(font
					(size 0.7 0.7)
					(thickness 0.15)
				)
				(justify right top)
			)
		)
		(fp_text user "Author: Antmicro"
			(at -0.939 3.399 0)
			(layer "F.Fab")
			(effects
				(font
					(size 0.7 0.7)
					(thickness 0.15)
				)
				(justify right top)
			)
		)
		(fp_text user "${REFERENCE}"
			(at 0 0 0)
			(layer "F.Fab")
			(effects
				(font
					(size 0.7 0.7)
					(thickness 0.15)
				)
				(justify right top)
			)
		)
		(pad "1" smd roundrect
			(at -0.48 0 180)
			(size 0.59 0.64)
			(layers "F.Cu" "F.Mask" "F.Paste")
			(roundrect_rratio 0.25)
			(net 122 "/USB-PD/12V_BOOT")
			(pintype "passive")
		)
		(pad "2" smd roundrect
			(at 0.48 0 180)
			(size 0.59 0.64)
			(layers "F.Cu" "F.Mask" "F.Paste")
			(roundrect_rratio 0.25)
			(net 120 "Net-(C27-Pad2)")
			(pintype "passive")
		)
	)
	(footprint "antmicro-footprints:C_0402_1005Metric"
		(layer "F.Cu")
		(at 139.75 91 90)
		(descr "Capacitor SMD 0402")
		(tags "capacitor SMD 0402")
		(property "Reference" "C26"
			(at -3.2 0.45 90)
			(layer "F.SilkS")
			(effects
				(font
					(size 0.7 0.7)
					(thickness 0.15)
				)
				(justify left bottom)
			)
		)
		(property "Value" "C_100n_0402"
			(at -1.022927 2.155213 90)
			(layer "F.Fab")
			(effects
				(font
					(size 0.7 0.7)
					(thickness 0.15)
				)
				(justify left bottom)
			)
		)
		(property "Datasheet" "https://www.murata.com/products/productdetail?partno=GRM155R61H104KE14%23"
			(at 0 0 90)
			(layer "F.Fab")
			(hide yes)
			(effects
				(font
					(size 1.27 1.27)
					(thickness 0.15)
				)
			)
		)
		(property "Description" "SMD Multilayer Ceramic Capacitor, 0.1 µF, 50 V, 0402 [1005 Metric], ± 10%, X5R, GRM Series"
			(at 0 0 90)
			(layer "F.Fab")
			(hide yes)
			(effects
				(font
					(size 1.27 1.27)
					(thickness 0.15)
				)
			)
		)
		(property "MPN" "GRM155R61H104KE14D"
			(at 0 0 90)
			(unlocked yes)
			(layer "F.Fab")
			(hide yes)
			(effects
				(font
					(size 1 1)
					(thickness 0.15)
				)
			)
		)
		(property "Val" "100n"
			(at 0 0 90)
			(unlocked yes)
			(layer "F.Fab")
			(hide yes)
			(effects
				(font
					(size 1 1)
					(thickness 0.15)
				)
			)
		)
		(property "Voltage" "50V"
			(at 0 0 90)
			(unlocked yes)
			(layer "F.Fab")
			(hide yes)
			(effects
				(font
					(size 1 1)
					(thickness 0.15)
				)
			)
		)
		(property "Dielectric" "X5R"
			(at 0 0 90)
			(unlocked yes)
			(layer "F.Fab")
			(hide yes)
			(effects
				(font
					(size 1 1)
					(thickness 0.15)
				)
			)
		)
		(property "Manufacturer" "Murata"
			(at 0 0 90)
			(unlocked yes)
			(layer "F.Fab")
			(hide yes)
			(effects
				(font
					(size 1 1)
					(thickness 0.15)
				)
			)
		)
		(property "License" "Apache-2.0"
			(at 0 0 90)
			(unlocked yes)
			(layer "F.Fab")
			(hide yes)
			(effects
				(font
					(size 1 1)
					(thickness 0.15)
				)
			)
		)
		(property "Author" "Antmicro"
			(at 0 0 90)
			(unlocked yes)
			(layer "F.Fab")
			(hide yes)
			(effects
				(font
					(size 1 1)
					(thickness 0.15)
				)
			)
		)
		(sheetname "/USB-PD/")
		(sheetfile "usb-pd.kicad_sch")
		(attr smd)
		(fp_rect
			(start -0.925 -0.47)
			(end 0.925 0.47)
			(stroke
				(width 0.05)
				(type default)
			)
			(fill no)
			(layer "F.CrtYd")
		)
		(fp_line
			(start 0.504 -0.25)
			(end 0.504 0.248)
			(stroke
				(width 0.15)
				(type solid)
			)
			(layer "F.Fab")
		)
		(fp_line
			(start -0.494 -0.25)
			(end 0.504 -0.25)
			(stroke
				(width 0.15)
				(type solid)
			)
			(layer "F.Fab")
		)
		(fp_line
			(start 0.504 0.248)
			(end -0.494 0.248)
			(stroke
				(width 0.15)
				(type solid)
			)
			(layer "F.Fab")
		)
		(fp_line
			(start -0.494 0.248)
			(end -0.494 -0.25)
			(stroke
				(width 0.15)
				(type solid)
			)
			(layer "F.Fab")
		)
		(fp_text user "License: Apache-2.0"
			(at -0.939 5.799 90)
			(layer "F.Fab")
			(effects
				(font
					(size 0.7 0.7)
					(thickness 0.15)
				)
				(justify left bottom)
			)
		)
		(fp_text user "${REFERENCE}"
			(at 0 0 90)
			(layer "F.Fab")
			(effects
				(font
					(size 0.7 0.7)
					(thickness 0.15)
				)
				(justify left bottom)
			)
		)
		(fp_text user "Author: Antmicro"
			(at -0.939 3.399 90)
			(layer "F.Fab")
			(effects
				(font
					(size 0.7 0.7)
					(thickness 0.15)
				)
				(justify left bottom)
			)
		)
		(pad "1" smd roundrect
			(at -0.48 0 90)
			(size 0.59 0.64)
			(layers "F.Cu" "F.Mask" "F.Paste")
			(roundrect_rratio 0.25)
			(net 66 "GND")
			(pintype "passive")
		)
		(pad "2" smd roundrect
			(at 0.48 0 90)
			(size 0.59 0.64)
			(layers "F.Cu" "F.Mask" "F.Paste")
			(roundrect_rratio 0.25)
			(net 115 "/USB-PD/VCC")
			(pintype "passive")
		)
	)
)
